#ISCELL
  mstr_misc dns *
  *
#ISCELL
  pure_quanta quanta_title_block_c *
  *
#ISCELL
  logical_power universal_gnd *
  page265_i1
#ISCELL
  logical_power universal_gnd *
  page265_i10
#CELL
  pure_quanta q_cap *
  page265_i11
#CELL
  pure_quanta q_res *
  page265_i12
#ISCELL
  logical_power universal_gnd *
  page265_i13
#CELL
  pure_quanta q_cap *
  page265_i14
#ISCELL
  logical_power vcc15 *
  page265_i15
#ISCELL
  logical_power universal_gnd *
  page265_i16
#CELL
  pure_quanta q_res *
  page265_i17
#CELL
  pure_quanta q_cap *
  page265_i18
#CELL
  pure_quanta q_res *
  page265_i19
#ISCELL
  logical_power universal_gnd *
  page265_i2
#CELL
  pure_quanta q_cap *
  page265_i20
#CELL
  pure_quanta q_cap *
  page265_i21
#CELL
  pure_quanta q_cap *
  page265_i22
#CELL
  pure_quanta q_cap *
  page265_i23
#CELL
  pure_quanta q_cap *
  page265_i24
#CELL
  pure_quanta q_cap *
  page265_i25
#CELL
  pure_quanta q_capp *
  page265_i26
#CELL
  pure_quanta q_capp *
  page265_i27
#CELL
  pure_quanta q_cap *
  page265_i28
#CELL
  pure_quanta q_cap *
  page265_i29
#CELL
  pure_quanta q_res *
  page265_i3
#CELL
  pure_quanta q_inductor *
  page265_i30
#ISCELL
  logical_power universal_gnd *
  page265_i31
#ISCELL
  logical_power vcc15 *
  page265_i32
#ISCELL
  logical_power universal_gnd *
  page265_i33
#CELL
  pure_quanta q_capp *
  page265_i34
#ISCELL
  logical_power vcc15 *
  page265_i35
#ISCELL
  logical_power universal_gnd *
  page265_i36
#CELL
  pure_quanta q_res *
  page265_i37
#ISCELL
  logical_power vcc15 *
  page265_i38
#ISCELL
  standard offpage *
  page265_i4
#ISCELL
  standard offpage *
  page265_i5
#ISCELL
  standard offpage *
  page265_i6
#CELL
  pure_quanta q_cap *
  page265_i7
#CELL
  pure_quanta isl99390frztr5935 *
  page265_i8
#ISCELL
  standard offpage *
  page265_i9
